# BASEBOARD_FAB2 (Tioga Pass) — schematic netlist excerpt (pin names and nets, part order shuffled) for the footprints in the layout excerpt that follows; sources: Cadence DE-HDL packaged netlist, KiCad conversion of Wiwynn_Tioga_Pass_MB.brd

C5D47  CAP_A  22.0UF 4V 20% X6S  pkg 0603V  page 42 : A = PVCCIN_CPU0 ; B = GND
CR1B1  DIODE  SDMK0340L EMPTY  pkg SM  page 161 : C = P5V_STBY ; A = FAN_PWM_OUT_SYS1_R
C5D39  CAP_A  22.0UF 4V 20% X6S  pkg 0603V  page 42 : A = PVCCIN_CPU0 ; B = GND

(kicad_pcb
	(version 20260206)
	(generator "pcbnew")
	(generator_version "10.0")
	(general
		(thickness 1.6)
		(legacy_teardrops no)
	)
	(paper "A4")
	(title_block
		(title "Wiwynn_Tioga_Pass_MB.brd")
		(comment 1 "Tioga Pass / footprints 1804-1806 of 4770")
	)
	(layers
		(0 "F.Cu" signal "TOP")
		(4 "In1.Cu" signal "L2GND")
		(6 "In2.Cu" signal "L3")
		(8 "In3.Cu" signal "L4GND")
		(10 "In4.Cu" signal "L5")
		(12 "In5.Cu" signal "L6GND")
		(14 "In6.Cu" signal "L7VCC")
		(16 "In7.Cu" signal "L8VCC")
		(18 "In8.Cu" signal "L9GND")
		(20 "In9.Cu" signal "L10")
		(22 "In10.Cu" signal "L11GND")
		(24 "In11.Cu" signal "L12")
		(26 "In12.Cu" signal "L13GND")
		(2 "B.Cu" signal "BOTTOM")
		(9 "F.Adhes" user "F.Adhesive")
		(11 "B.Adhes" user "B.Adhesive")
		(13 "F.Paste" user "Package Geometry/Pastemask Top")
		(15 "B.Paste" user "Package Geometry/Pastemask Bottom")
		(5 "F.SilkS" user "Ref Des/Silkscreen Top")
		(7 "B.SilkS" user "Ref Des/Silkscreen Bottom")
		(1 "F.Mask" user "Board Geometry/Soldermask Top")
		(3 "B.Mask" user "Board Geometry/Soldermask Bottom")
		(17 "Dwgs.User" user "User.Drawings")
		(19 "Cmts.User" user "User.Comments")
		(21 "Eco1.User" user "User.Eco1")
		(23 "Eco2.User" user "User.Eco2")
		(25 "Edge.Cuts" user "Board Geometry/Outline")
		(27 "Margin" user)
		(31 "F.CrtYd" user "Package Geometry/Place Bound Top")
		(29 "B.CrtYd" user "Package Geometry/Place Bound Bottom")
		(35 "F.Fab" user "Ref Des/Assembly Top")
		(33 "B.Fab" user "Ref Des/Assembly Bottom")
	)
	(footprint ""
		(layer "F.Cu")
		(at 268.165072 -73.318116)
		(property "Reference" "C5D47"
			(at 0 0 0)
			(layer "F.SilkS")
			(hide yes)
			(effects
				(font
					(size 1.27 1.27)
				)
			)
		)
		(property "Value" ""
			(at 0 0 0)
			(layer "F.Fab")
			(effects
				(font
					(size 1.27 1.27)
				)
			)
		)
		(duplicate_pad_numbers_are_jumpers no)
		(fp_poly
			(pts
				(xy -0.4953 -0.2032) (xy 0.4953 -0.2032) (xy 0.4953 1.6002) (xy -0.4953 1.6002)
			)
			(stroke
				(width 0)
				(type default)
			)
			(fill no)
			(layer "F.CrtYd")
		)
		(fp_line
			(start -0.4953 -0.2032)
			(end 0.4953 -0.2032)
			(stroke
				(width 0.1)
				(type default)
			)
			(layer "F.Fab")
		)
		(fp_line
			(start -0.4953 1.6002)
			(end -0.4953 -0.2032)
			(stroke
				(width 0.1)
				(type default)
			)
			(layer "F.Fab")
		)
		(fp_line
			(start 0.4953 -0.2032)
			(end 0.4953 1.6002)
			(stroke
				(width 0.1)
				(type default)
			)
			(layer "F.Fab")
		)
		(fp_line
			(start 0.4953 1.6002)
			(end -0.4953 1.6002)
			(stroke
				(width 0.1)
				(type default)
			)
			(layer "F.Fab")
		)
		(pad "1" smd rect
			(at 0 0)
			(size 0.762 0.889)
			(layers "F.Cu" "F.Mask" "F.Paste")
			(net "PVCCIN_CPU0")
		)
		(pad "2" smd rect
			(at 0 1.397)
			(size 0.762 0.889)
			(layers "F.Cu" "F.Mask" "F.Paste")
			(net "GND")
		)
		(zone
			(layer "F.Cu")
			(hatch none 0.5)
			(connect_pads
				(clearance 0)
			)
			(min_thickness 0.25)
			(keepout
				(tracks not_allowed)
				(vias allowed)
				(pads allowed)
				(copperpour not_allowed)
				(footprints allowed)
			)
			(placement
				(enabled no)
				(sheetname "")
			)
			(fill
				(thermal_gap 0.5)
				(thermal_bridge_width 0.5)
				(island_removal_mode 0)
			)
			(polygon
				(pts
					(xy 267.784072 -72.873616) (xy 268.546072 -72.873616) (xy 268.546072 -72.365616) (xy 267.784072 -72.365616)
				)
			)
		)
	)
	(footprint ""
		(layer "F.Cu")
		(at 258.208272 -73.318116)
		(property "Reference" "C5D39"
			(at 0 0 0)
			(layer "F.SilkS")
			(hide yes)
			(effects
				(font
					(size 1.27 1.27)
				)
			)
		)
		(property "Value" ""
			(at 0 0 0)
			(layer "F.Fab")
			(effects
				(font
					(size 1.27 1.27)
				)
			)
		)
		(duplicate_pad_numbers_are_jumpers no)
		(fp_poly
			(pts
				(xy -0.4953 -0.2032) (xy 0.4953 -0.2032) (xy 0.4953 1.6002) (xy -0.4953 1.6002)
			)
			(stroke
				(width 0)
				(type default)
			)
			(fill no)
			(layer "F.CrtYd")
		)
		(fp_line
			(start -0.4953 -0.2032)
			(end 0.4953 -0.2032)
			(stroke
				(width 0.1)
				(type default)
			)
			(layer "F.Fab")
		)
		(fp_line
			(start -0.4953 1.6002)
			(end -0.4953 -0.2032)
			(stroke
				(width 0.1)
				(type default)
			)
			(layer "F.Fab")
		)
		(fp_line
			(start 0.4953 -0.2032)
			(end 0.4953 1.6002)
			(stroke
				(width 0.1)
				(type default)
			)
			(layer "F.Fab")
		)
		(fp_line
			(start 0.4953 1.6002)
			(end -0.4953 1.6002)
			(stroke
				(width 0.1)
				(type default)
			)
			(layer "F.Fab")
		)
		(pad "1" smd rect
			(at 0 0)
			(size 0.762 0.889)
			(layers "F.Cu" "F.Mask" "F.Paste")
			(net "PVCCIN_CPU0")
		)
		(pad "2" smd rect
			(at 0 1.397)
			(size 0.762 0.889)
			(layers "F.Cu" "F.Mask" "F.Paste")
			(net "GND")
		)
		(zone
			(layer "F.Cu")
			(hatch none 0.5)
			(connect_pads
				(clearance 0)
			)
			(min_thickness 0.25)
			(keepout
				(tracks not_allowed)
				(vias allowed)
				(pads allowed)
				(copperpour not_allowed)
				(footprints allowed)
			)
			(placement
				(enabled no)
				(sheetname "")
			)
			(fill
				(thermal_gap 0.5)
				(thermal_bridge_width 0.5)
				(island_removal_mode 0)
			)
			(polygon
				(pts
					(xy 257.827272 -72.873616) (xy 258.589272 -72.873616) (xy 258.589272 -72.365616) (xy 257.827272 -72.365616)
				)
			)
		)
	)
	(footprint ""
		(layer "F.Cu")
		(at 21.29028 -121.43232 -90)
		(property "Reference" "CR1B1"
			(at 3.22199 1.60528 0)
			(unlocked yes)
			(layer "F.SilkS")
			(effects
				(font
					(size 0.7874 0.5842)
					(thickness 0.1524)
				)
				(justify left)
			)
		)
		(property "Value" ""
			(at 0 0 270)
			(layer "F.Fab")
			(effects
				(font
					(size 1.27 1.27)
				)
			)
		)
		(duplicate_pad_numbers_are_jumpers no)
		(fp_line
			(start -1.335278 2.576068)
			(end -1.335278 1.664462)
			(stroke
				(width 0.1524)
				(type default)
			)
			(layer "F.SilkS")
		)
		(fp_line
			(start -1.8161 1.664462)
			(end -1.335278 0.831596)
			(stroke
				(width 0.1524)
				(type default)
			)
			(layer "F.SilkS")
		)
		(fp_line
			(start -1.335278 1.664462)
			(end -1.8161 1.664462)
			(stroke
				(width 0.1524)
				(type default)
			)
			(layer "F.SilkS")
		)
		(fp_line
			(start -0.854456 1.664462)
			(end -1.335278 1.664462)
			(stroke
				(width 0.1524)
				(type default)
			)
			(layer "F.SilkS")
		)
		(fp_line
			(start -1.335278 0.831596)
			(end -0.854456 1.664462)
			(stroke
				(width 0.1524)
				(type default)
			)
			(layer "F.SilkS")
		)
		(fp_line
			(start -0.854456 0.831596)
			(end -1.8161 0.831596)
			(stroke
				(width 0.1524)
				(type default)
			)
			(layer "F.SilkS")
		)
		(fp_line
			(start -1.335278 -0.291846)
			(end -1.335278 0.831596)
			(stroke
				(width 0.1524)
				(type default)
			)
			(layer "F.SilkS")
		)
		(fp_rect
			(start 0.67437 2.04216)
			(end -0.67437 0.24384)
			(stroke
				(width 0)
				(type default)
			)
			(fill no)
			(layer "F.CrtYd")
		)
		(fp_line
			(start -0.67437 2.04216)
			(end 0.67437 2.04216)
			(stroke
				(width 0.1)
				(type default)
			)
			(layer "F.Fab")
		)
		(fp_line
			(start 0.67437 2.04216)
			(end 0.67437 0.24384)
			(stroke
				(width 0.1)
				(type default)
			)
			(layer "F.Fab")
		)
		(fp_line
			(start -1.8161 1.664462)
			(end -1.335278 0.831596)
			(stroke
				(width 0.1)
				(type default)
			)
			(layer "F.Fab")
		)
		(fp_line
			(start -1.335278 1.664462)
			(end -1.335278 2.576068)
			(stroke
				(width 0.1)
				(type default)
			)
			(layer "F.Fab")
		)
		(fp_line
			(start -0.854456 1.664462)
			(end -1.8161 1.664462)
			(stroke
				(width 0.1)
				(type default)
			)
			(layer "F.Fab")
		)
		(fp_line
			(start -1.335278 0.831596)
			(end -0.854456 1.664462)
			(stroke
				(width 0.1)
				(type default)
			)
			(layer "F.Fab")
		)
		(fp_line
			(start -1.335278 0.831596)
			(end -1.335278 -0.291846)
			(stroke
				(width 0.1)
				(type default)
			)
			(layer "F.Fab")
		)
		(fp_line
			(start -0.854456 0.831596)
			(end -1.8161 0.831596)
			(stroke
				(width 0.1)
				(type default)
			)
			(layer "F.Fab")
		)
		(fp_line
			(start -0.67437 0.24384)
			(end -0.67437 2.04216)
			(stroke
				(width 0.1)
				(type default)
			)
			(layer "F.Fab")
		)
		(fp_line
			(start 0.67437 0.24384)
			(end -0.67437 0.24384)
			(stroke
				(width 0.1)
				(type default)
			)
			(layer "F.Fab")
		)
		(pad "1" smd rect
			(at 0 0 270)
			(size 0.4064 1.016)
			(layers "F.Cu" "F.Mask" "F.Paste")
			(net "P5V_STBY")
		)
		(pad "2" smd rect
			(at 0 2.286 270)
			(size 0.4064 1.016)
			(layers "F.Cu" "F.Mask" "F.Paste")
			(net "FAN_PWM_OUT_SYS1_R")
		)
	)
)
